(kicad_pcb
	(version 20260206)
	(generator "pcbnew")
	(generator_version "10.0")
	(general
		(thickness 1.6)
		(legacy_teardrops no)
	)
	(paper "A4")
	(title_block
		(title "Wiwynn_Tioga_Pass_MB.brd")
		(comment 1 "Tioga Pass / footprint 190 of 4770 (U2D1), pads 2824-2910 of 3647")
	)
	(layers
		(0 "F.Cu" signal "TOP")
		(4 "In1.Cu" signal "L2GND")
		(6 "In2.Cu" signal "L3")
		(8 "In3.Cu" signal "L4GND")
		(10 "In4.Cu" signal "L5")
		(12 "In5.Cu" signal "L6GND")
		(14 "In6.Cu" signal "L7VCC")
		(16 "In7.Cu" signal "L8VCC")
		(18 "In8.Cu" signal "L9GND")
		(20 "In9.Cu" signal "L10")
		(22 "In10.Cu" signal "L11GND")
		(24 "In11.Cu" signal "L12")
		(26 "In12.Cu" signal "L13GND")
		(2 "B.Cu" signal "BOTTOM")
		(9 "F.Adhes" user "F.Adhesive")
		(11 "B.Adhes" user "B.Adhesive")
		(13 "F.Paste" user "Package Geometry/Pastemask Top")
		(15 "B.Paste" user "Package Geometry/Pastemask Bottom")
		(5 "F.SilkS" user "Ref Des/Silkscreen Top")
		(7 "B.SilkS" user "Ref Des/Silkscreen Bottom")
		(1 "F.Mask" user "Board Geometry/Soldermask Top")
		(3 "B.Mask" user "Board Geometry/Soldermask Bottom")
		(17 "Dwgs.User" user "User.Drawings")
		(19 "Cmts.User" user "User.Comments")
		(21 "Eco1.User" user "User.Eco1")
		(23 "Eco2.User" user "User.Eco2")
		(25 "Edge.Cuts" user "Board Geometry/Outline")
		(27 "Margin" user)
		(31 "F.CrtYd" user "Package Geometry/Place Bound Top")
		(29 "B.CrtYd" user "Package Geometry/Place Bound Bottom")
		(35 "F.Fab" user "Ref Des/Assembly Top")
		(33 "B.Fab" user "Ref Des/Assembly Bottom")
	)
	(footprint ""
		(layer "F.Cu")
		(at 104.99979 -76.550012 180)
		(property "Reference" "U2D1"
			(at 25.19299 30.484318 0)
			(unlocked yes)
			(layer "F.SilkS")
			(effects
				(font
					(size 0.7874 0.5842)
					(thickness 0.1524)
				)
			)
		)
		(property "Value" ""
			(at 0 0 180)
			(layer "F.Fab")
			(effects
				(font
					(size 1.27 1.27)
				)
			)
		)
		(duplicate_pad_numbers_are_jumpers no)
		(pad "EA26" smd circle
			(at -15.787878 24.426672)
			(size 0.4318 0.4318)
			(layers "F.Cu" "F.Mask" "F.Paste")
			(net "M_L_DQS_DN<15>")
		)
		(pad "EA28" smd circle
			(at -14.071092 24.426672)
			(size 0.4318 0.4318)
			(layers "F.Cu" "F.Mask" "F.Paste")
			(net "M_L_DQ<53>")
		)
		(pad "EA30" smd circle
			(at -12.354052 24.426672)
			(size 0.4318 0.4318)
			(layers "F.Cu" "F.Mask" "F.Paste")
			(net "M_L_DQ<42>")
		)
		(pad "EA32" smd circle
			(at -10.637012 24.426672)
			(size 0.4318 0.4318)
			(layers "F.Cu" "F.Mask" "F.Paste")
			(net "M_L_DQS_DN<14>")
		)
		(pad "EA34" smd circle
			(at -8.919972 24.426672)
			(size 0.4318 0.4318)
			(layers "F.Cu" "F.Mask" "F.Paste")
			(net "M_L_DQ<45>")
		)
		(pad "EA36" smd circle
			(at -7.202932 24.426672)
			(size 0.4318 0.4318)
			(layers "F.Cu" "F.Mask" "F.Paste")
			(net "M_K_DQ<34>")
		)
		(pad "EA38" smd circle
			(at -5.485892 24.426672)
			(size 0.4318 0.4318)
			(layers "F.Cu" "F.Mask" "F.Paste")
			(net "M_K_DQS_DN<13>")
		)
		(pad "EA40" smd circle
			(at -3.769106 24.426672)
			(size 0.4318 0.4318)
			(layers "F.Cu" "F.Mask" "F.Paste")
			(net "M_K_DQ<37>")
		)
		(pad "EA42" smd circle
			(at -2.052066 24.426672)
			(size 0.4318 0.4318)
			(layers "F.Cu" "F.Mask" "F.Paste")
			(net "GND")
		)
		(pad "EA44" smd circle
			(at 1.193546 22.626828)
			(size 0.508 0.508)
			(layers "F.Cu" "F.Mask" "F.Paste")
			(net "TP_CPU1_RSVD_19")
		)
		(pad "EA46" smd circle
			(at 2.910586 22.626828)
			(size 0.4318 0.4318)
			(layers "F.Cu" "F.Mask" "F.Paste")
			(net "M_K_MA<17>")
		)
		(pad "EA48" smd circle
			(at 4.627626 22.626828)
			(size 0.4318 0.4318)
			(layers "F.Cu" "F.Mask" "F.Paste")
			(net "M_K_ODT<3>")
		)
		(pad "EA50" smd circle
			(at 6.344412 22.626828)
			(size 0.4318 0.4318)
			(layers "F.Cu" "F.Mask" "F.Paste")
			(net "M_K_ODT<2>")
		)
		(pad "EA52" smd circle
			(at 8.061452 22.626828)
			(size 0.4318 0.4318)
			(layers "F.Cu" "F.Mask" "F.Paste")
			(net "M_K_MA<16>")
		)
		(pad "EA54" smd circle
			(at 9.778492 22.626828)
			(size 0.4318 0.4318)
			(layers "F.Cu" "F.Mask" "F.Paste")
			(net "M_K_BA<1>")
		)
		(pad "EA56" smd circle
			(at 11.495532 22.626828)
			(size 0.4318 0.4318)
			(layers "F.Cu" "F.Mask" "F.Paste")
			(net "M_K_CLK_DP<2>")
		)
		(pad "EA58" smd circle
			(at 13.212572 22.626828)
			(size 0.4318 0.4318)
			(layers "F.Cu" "F.Mask" "F.Paste")
			(net "M_K_MA<5>")
		)
		(pad "EA60" smd circle
			(at 14.929612 22.626828)
			(size 0.4318 0.4318)
			(layers "F.Cu" "F.Mask" "F.Paste")
			(net "M_K_MA<7>")
		)
		(pad "EA62" smd circle
			(at 16.646398 22.626828)
			(size 0.4318 0.4318)
			(layers "F.Cu" "F.Mask" "F.Paste")
			(net "M_K_CKE<2>")
		)
		(pad "EA64" smd circle
			(at 18.363438 22.626828)
			(size 0.4318 0.4318)
			(layers "F.Cu" "F.Mask" "F.Paste")
			(net "GND")
		)
		(pad "EA66" smd circle
			(at 20.080478 22.626828)
			(size 0.4318 0.4318)
			(layers "F.Cu" "F.Mask" "F.Paste")
			(net "M_L_ECC<7>")
		)
		(pad "EA68" smd circle
			(at 21.797518 22.626828)
			(size 0.4318 0.4318)
			(layers "F.Cu" "F.Mask" "F.Paste")
			(net "M_L_ECC<1>")
		)
		(pad "EA70" smd circle
			(at 23.514558 22.626828)
			(size 0.4318 0.4318)
			(layers "F.Cu" "F.Mask" "F.Paste")
			(net "GND")
		)
		(pad "EA72" smd circle
			(at 25.231598 22.626828)
			(size 0.4318 0.4318)
			(layers "F.Cu" "F.Mask" "F.Paste")
			(net "M_L_DQ<30>")
		)
		(pad "EA74" smd circle
			(at 26.948384 22.626828)
			(size 0.4318 0.4318)
			(layers "F.Cu" "F.Mask" "F.Paste")
			(net "M_L_DQ<28>")
		)
		(pad "EA76" smd circle
			(at 28.665424 22.626828)
			(size 0.4318 0.4318)
			(layers "F.Cu" "F.Mask" "F.Paste")
			(net "GND")
		)
		(pad "EA78" smd circle
			(at 30.382464 22.626828)
			(size 0.4318 0.4318)
			(layers "F.Cu" "F.Mask" "F.Paste")
			(net "GND")
		)
		(pad "EA80" smd circle
			(at 32.099504 22.626828)
			(size 0.4318 0.4318)
			(layers "F.Cu" "F.Mask" "F.Paste")
			(net "GND")
		)
		(pad "EA82" smd circle
			(at 33.816544 22.626828)
			(size 0.4318 0.4318)
			(layers "F.Cu" "F.Mask" "F.Paste")
			(net "GND")
		)
		(pad "EA84" smd custom
			(at 35.533584 22.626828 225)
			(size 0.10795 0.10795)
			(layers "F.Cu" "F.Mask" "F.Paste")
			(net "GND")
			(options
				(clearance outline)
				(anchor circle)
			)
			(primitives
				(gr_poly
					(pts
						(arc
							(start 0.2159 -0.0381)
							(mid 0 -0.254)
							(end -0.2159 -0.0381)
						)
						(arc
							(start -0.2159 0.0381)
							(mid 0 0.254)
							(end 0.2159 0.0381)
						)
					)
					(width 0)
					(fill yes)
				)
			)
		)
		(pad "EB3" smd custom
			(at -35.533584 24.921972 135)
			(size 0.10795 0.10795)
			(layers "F.Cu" "F.Mask" "F.Paste")
			(net "TP_CPU1_RSVD_18")
			(options
				(clearance outline)
				(anchor circle)
			)
			(primitives
				(gr_poly
					(pts
						(arc
							(start 0.2159 -0.0381)
							(mid 0 -0.254)
							(end -0.2159 -0.0381)
						)
						(arc
							(start -0.2159 0.0381)
							(mid 0 0.254)
							(end 0.2159 0.0381)
						)
					)
					(width 0)
					(fill yes)
				)
			)
		)
		(pad "EB5" smd custom
			(at -33.816544 24.921972 135)
			(size 0.10795 0.10795)
			(layers "F.Cu" "F.Mask" "F.Paste")
			(net "TP_CPU1_RSVD_17")
			(options
				(clearance outline)
				(anchor circle)
			)
			(primitives
				(gr_poly
					(pts
						(arc
							(start 0.2159 -0.0381)
							(mid 0 -0.254)
							(end -0.2159 -0.0381)
						)
						(arc
							(start -0.2159 0.0381)
							(mid 0 0.254)
							(end 0.2159 0.0381)
						)
					)
					(width 0)
					(fill yes)
				)
			)
		)
		(pad "EB7" smd circle
			(at -32.099504 24.921972)
			(size 0.4318 0.4318)
			(layers "F.Cu" "F.Mask" "F.Paste")
			(net "TP_P3E_CPU1_PE1_RSR3_TXP<14>")
		)
		(pad "EB9" smd circle
			(at -30.382464 24.921972)
			(size 0.4318 0.4318)
			(layers "F.Cu" "F.Mask" "F.Paste")
			(net "P3E_CPU1_PE3_MP_TXN<4>")
		)
		(pad "EB11" smd circle
			(at -28.665424 24.921972)
			(size 0.4318 0.4318)
			(layers "F.Cu" "F.Mask" "F.Paste")
			(net "P3E_CPU1_PE3_MP_TXP<2>")
		)
		(pad "EB13" smd circle
			(at -26.948384 24.921972)
			(size 0.4318 0.4318)
			(layers "F.Cu" "F.Mask" "F.Paste")
			(net "GND")
		)
		(pad "EB15" smd circle
			(at -25.231598 24.921972)
			(size 0.4318 0.4318)
			(layers "F.Cu" "F.Mask" "F.Paste")
			(net "PVCCIO_CPU1")
		)
		(pad "EB21" smd custom
			(at -20.080478 24.921972 120)
			(size 0.10795 0.10795)
			(layers "F.Cu" "F.Mask" "F.Paste")
			(net "M_K_DQ<59>")
			(options
				(clearance outline)
				(anchor circle)
			)
			(primitives
				(gr_poly
					(pts
						(arc
							(start 0.2159 -0.0381)
							(mid 0 -0.254)
							(end -0.2159 -0.0381)
						)
						(arc
							(start -0.2159 0.0381)
							(mid 0 0.254)
							(end 0.2159 0.0381)
						)
					)
					(width 0)
					(fill yes)
				)
			)
		)
		(pad "EB23" smd circle
			(at -18.363438 24.921972)
			(size 0.4318 0.4318)
			(layers "F.Cu" "F.Mask" "F.Paste")
			(net "GND")
		)
		(pad "EB25" smd circle
			(at -16.646398 24.921972)
			(size 0.4318 0.4318)
			(layers "F.Cu" "F.Mask" "F.Paste")
			(net "GND")
		)
		(pad "EB27" smd circle
			(at -14.929612 24.921972)
			(size 0.4318 0.4318)
			(layers "F.Cu" "F.Mask" "F.Paste")
			(net "GND")
		)
		(pad "EB29" smd circle
			(at -13.212572 24.921972)
			(size 0.4318 0.4318)
			(layers "F.Cu" "F.Mask" "F.Paste")
			(net "GND")
		)
		(pad "EB31" smd circle
			(at -11.495532 24.921972)
			(size 0.4318 0.4318)
			(layers "F.Cu" "F.Mask" "F.Paste")
			(net "GND")
		)
		(pad "EB33" smd circle
			(at -9.778492 24.921972)
			(size 0.4318 0.4318)
			(layers "F.Cu" "F.Mask" "F.Paste")
			(net "GND")
		)
		(pad "EB35" smd circle
			(at -8.061452 24.921972)
			(size 0.4318 0.4318)
			(layers "F.Cu" "F.Mask" "F.Paste")
			(net "GND")
		)
		(pad "EB37" smd circle
			(at -6.344412 24.921972)
			(size 0.4318 0.4318)
			(layers "F.Cu" "F.Mask" "F.Paste")
			(net "GND")
		)
		(pad "EB39" smd circle
			(at -4.627626 24.921972)
			(size 0.4318 0.4318)
			(layers "F.Cu" "F.Mask" "F.Paste")
			(net "GND")
		)
		(pad "EB41" smd circle
			(at -2.910586 24.921972)
			(size 0.4318 0.4318)
			(layers "F.Cu" "F.Mask" "F.Paste")
			(net "GND")
		)
		(pad "EB45" smd circle
			(at 2.052066 23.122128)
			(size 0.4318 0.4318)
			(layers "F.Cu" "F.Mask" "F.Paste")
			(net "M_K_CS_N<7>")
		)
		(pad "EB47" smd circle
			(at 3.769106 23.122128)
			(size 0.4318 0.4318)
			(layers "F.Cu" "F.Mask" "F.Paste")
			(net "M_K_CS_N<3>")
		)
		(pad "EB49" smd circle
			(at 5.485892 23.122128)
			(size 0.4318 0.4318)
			(layers "F.Cu" "F.Mask" "F.Paste")
			(net "M_K_CS_N<5>")
		)
		(pad "EB51" smd circle
			(at 7.202932 23.122128)
			(size 0.4318 0.4318)
			(layers "F.Cu" "F.Mask" "F.Paste")
			(net "M_K_CS_N<4>")
		)
		(pad "EB53" smd circle
			(at 8.919972 23.122128)
			(size 0.4318 0.4318)
			(layers "F.Cu" "F.Mask" "F.Paste")
			(net "M_K_MA<0>")
		)
		(pad "EB55" smd circle
			(at 10.637012 23.122128)
			(size 0.4318 0.4318)
			(layers "F.Cu" "F.Mask" "F.Paste")
			(net "M_K_CLK_DP<0>")
		)
		(pad "EB57" smd circle
			(at 12.354052 23.122128)
			(size 0.4318 0.4318)
			(layers "F.Cu" "F.Mask" "F.Paste")
			(net "M_K_MA<3>")
		)
		(pad "EB59" smd circle
			(at 14.071092 23.122128)
			(size 0.4318 0.4318)
			(layers "F.Cu" "F.Mask" "F.Paste")
			(net "M_K_MA<8>")
		)
		(pad "EB61" smd circle
			(at 15.787878 23.122128)
			(size 0.4318 0.4318)
			(layers "F.Cu" "F.Mask" "F.Paste")
			(net "M_K_MA<11>")
		)
		(pad "EB63" smd custom
			(at 17.504918 23.122128 180)
			(size 0.10795 0.10795)
			(layers "F.Cu" "F.Mask" "F.Paste")
			(net "M_K_CKE<3>")
			(options
				(clearance outline)
				(anchor circle)
			)
			(primitives
				(gr_poly
					(pts
						(arc
							(start 0.2159 -0.0381)
							(mid 0 -0.254)
							(end -0.2159 -0.0381)
						)
						(arc
							(start -0.2159 0.0381)
							(mid 0 0.254)
							(end 0.2159 0.0381)
						)
					)
					(width 0)
					(fill yes)
				)
			)
		)
		(pad "EB65" smd custom
			(at 19.221958 23.122128 180)
			(size 0.10795 0.10795)
			(layers "F.Cu" "F.Mask" "F.Paste")
			(net "GND")
			(options
				(clearance outline)
				(anchor circle)
			)
			(primitives
				(gr_poly
					(pts
						(arc
							(start 0.2159 -0.0381)
							(mid 0 -0.254)
							(end -0.2159 -0.0381)
						)
						(arc
							(start -0.2159 0.0381)
							(mid 0 0.254)
							(end 0.2159 0.0381)
						)
					)
					(width 0)
					(fill yes)
				)
			)
		)
		(pad "EB67" smd custom
			(at 20.938998 23.122128 180)
			(size 0.10795 0.10795)
			(layers "F.Cu" "F.Mask" "F.Paste")
			(net "M_L_DQS_DN<8>")
			(options
				(clearance outline)
				(anchor circle)
			)
			(primitives
				(gr_poly
					(pts
						(arc
							(start 0.2159 -0.0381)
							(mid 0 -0.254)
							(end -0.2159 -0.0381)
						)
						(arc
							(start -0.2159 0.0381)
							(mid 0 0.254)
							(end 0.2159 0.0381)
						)
					)
					(width 0)
					(fill yes)
				)
			)
		)
		(pad "EB69" smd custom
			(at 22.656038 23.122128 180)
			(size 0.10795 0.10795)
			(layers "F.Cu" "F.Mask" "F.Paste")
			(net "GND")
			(options
				(clearance outline)
				(anchor circle)
			)
			(primitives
				(gr_poly
					(pts
						(arc
							(start 0.2159 -0.0381)
							(mid 0 -0.254)
							(end -0.2159 -0.0381)
						)
						(arc
							(start -0.2159 0.0381)
							(mid 0 0.254)
							(end 0.2159 0.0381)
						)
					)
					(width 0)
					(fill yes)
				)
			)
		)
		(pad "EB71" smd circle
			(at 24.373078 23.122128)
			(size 0.4318 0.4318)
			(layers "F.Cu" "F.Mask" "F.Paste")
			(net "M_L_DQ<26>")
		)
		(pad "EB73" smd circle
			(at 26.090118 23.122128)
			(size 0.4318 0.4318)
			(layers "F.Cu" "F.Mask" "F.Paste")
			(net "M_L_DQS_DN<12>")
		)
		(pad "EB75" smd circle
			(at 27.806904 23.122128)
			(size 0.4318 0.4318)
			(layers "F.Cu" "F.Mask" "F.Paste")
			(net "M_L_DQ<29>")
		)
		(pad "EB77" smd circle
			(at 29.523944 23.122128)
			(size 0.4318 0.4318)
			(layers "F.Cu" "F.Mask" "F.Paste")
			(net "M_L_DQ<19>")
		)
		(pad "EB79" smd circle
			(at 31.240984 23.122128)
			(size 0.4318 0.4318)
			(layers "F.Cu" "F.Mask" "F.Paste")
			(net "M_L_DQS_DP<2>")
		)
		(pad "EB81" smd circle
			(at 32.958024 23.122128)
			(size 0.4318 0.4318)
			(layers "F.Cu" "F.Mask" "F.Paste")
			(net "M_L_DQ<21>")
		)
		(pad "EB83" smd custom
			(at 34.675064 23.122128 225)
			(size 0.10795 0.10795)
			(layers "F.Cu" "F.Mask" "F.Paste")
			(net "GND")
			(options
				(clearance outline)
				(anchor circle)
			)
			(primitives
				(gr_poly
					(pts
						(arc
							(start 0.2159 -0.0381)
							(mid 0 -0.254)
							(end -0.2159 -0.0381)
						)
						(arc
							(start -0.2159 0.0381)
							(mid 0 0.254)
							(end 0.2159 0.0381)
						)
					)
					(width 0)
					(fill yes)
				)
			)
		)
		(pad "EB85" smd custom
			(at 36.392104 23.122128 270)
			(size 0.10795 0.10795)
			(layers "F.Cu" "F.Mask" "F.Paste")
			(net "TP_CPU1_RSVD_16")
			(options
				(clearance outline)
				(anchor circle)
			)
			(primitives
				(gr_poly
					(pts
						(arc
							(start 0.2159 -0.0381)
							(mid 0 -0.254)
							(end -0.2159 -0.0381)
						)
						(arc
							(start -0.2159 0.0381)
							(mid 0 0.254)
							(end 0.2159 0.0381)
						)
					)
					(width 0)
					(fill yes)
				)
			)
		)
		(pad "EC4" smd custom
			(at -34.675064 25.417526 135)
			(size 0.10795 0.10795)
			(layers "F.Cu" "F.Mask" "F.Paste")
			(net "TP_CPU1_RSVD_14")
			(options
				(clearance outline)
				(anchor circle)
			)
			(primitives
				(gr_poly
					(pts
						(arc
							(start 0.2159 -0.0381)
							(mid 0 -0.254)
							(end -0.2159 -0.0381)
						)
						(arc
							(start -0.2159 0.0381)
							(mid 0 0.254)
							(end 0.2159 0.0381)
						)
					)
					(width 0)
					(fill yes)
				)
			)
		)
		(pad "EC6" smd custom
			(at -32.958024 25.417526 135)
			(size 0.10795 0.10795)
			(layers "F.Cu" "F.Mask" "F.Paste")
			(net "GND")
			(options
				(clearance outline)
				(anchor circle)
			)
			(primitives
				(gr_poly
					(pts
						(arc
							(start 0.2159 -0.0381)
							(mid 0 -0.254)
							(end -0.2159 -0.0381)
						)
						(arc
							(start -0.2159 0.0381)
							(mid 0 0.254)
							(end 0.2159 0.0381)
						)
					)
					(width 0)
					(fill yes)
				)
			)
		)
		(pad "EC8" smd circle
			(at -31.240984 25.417526)
			(size 0.4318 0.4318)
			(layers "F.Cu" "F.Mask" "F.Paste")
			(net "TP_P3E_CPU1_PE1_RSR3_TXP<15>")
		)
		(pad "EC10" smd circle
			(at -29.523944 25.417526)
			(size 0.4318 0.4318)
			(layers "F.Cu" "F.Mask" "F.Paste")
			(net "GND")
		)
		(pad "EC12" smd circle
			(at -27.806904 25.417526)
			(size 0.4318 0.4318)
			(layers "F.Cu" "F.Mask" "F.Paste")
			(net "P3E_CPU1_PE3_MP_TXN<2>")
		)
		(pad "EC14" smd circle
			(at -26.090118 25.417526)
			(size 0.4318 0.4318)
			(layers "F.Cu" "F.Mask" "F.Paste")
			(net "P3E_CPU1_PE3_MP_TXP<0>")
		)
		(pad "EC16" smd custom
			(at -24.373078 25.417526 180)
			(size 0.10795 0.10795)
			(layers "F.Cu" "F.Mask" "F.Paste")
			(net "TP_CPU1_RSVD_15")
			(options
				(clearance outline)
				(anchor circle)
			)
			(primitives
				(gr_poly
					(pts
						(arc
							(start 0.2159 -0.0381)
							(mid 0 -0.254)
							(end -0.2159 -0.0381)
						)
						(arc
							(start -0.2159 0.0381)
							(mid 0 0.254)
							(end 0.2159 0.0381)
						)
					)
					(width 0)
					(fill yes)
				)
			)
		)
		(pad "EC22" smd custom
			(at -19.221958 25.417526 120)
			(size 0.10795 0.10795)
			(layers "F.Cu" "F.Mask" "F.Paste")
			(net "M_K_DQ<62>")
			(options
				(clearance outline)
				(anchor circle)
			)
			(primitives
				(gr_poly
					(pts
						(arc
							(start 0.2159 -0.0381)
							(mid 0 -0.254)
							(end -0.2159 -0.0381)
						)
						(arc
							(start -0.2159 0.0381)
							(mid 0 0.254)
							(end 0.2159 0.0381)
						)
					)
					(width 0)
					(fill yes)
				)
			)
		)
		(pad "EC24" smd circle
			(at -17.504918 25.417526)
			(size 0.4318 0.4318)
			(layers "F.Cu" "F.Mask" "F.Paste")
			(net "M_L_DQ<51>")
		)
		(pad "EC26" smd circle
			(at -15.787878 25.417526)
			(size 0.4318 0.4318)
			(layers "F.Cu" "F.Mask" "F.Paste")
			(net "M_L_DQS_DP<6>")
		)
		(pad "EC28" smd circle
			(at -14.071092 25.417526)
			(size 0.4318 0.4318)
			(layers "F.Cu" "F.Mask" "F.Paste")
			(net "M_L_DQ<48>")
		)
		(pad "EC30" smd circle
			(at -12.354052 25.417526)
			(size 0.4318 0.4318)
			(layers "F.Cu" "F.Mask" "F.Paste")
			(net "M_L_DQ<43>")
		)
		(pad "EC32" smd circle
			(at -10.637012 25.417526)
			(size 0.4318 0.4318)
			(layers "F.Cu" "F.Mask" "F.Paste")
			(net "M_L_DQS_DP<5>")
		)
		(pad "EC34" smd circle
			(at -8.919972 25.417526)
			(size 0.4318 0.4318)
			(layers "F.Cu" "F.Mask" "F.Paste")
			(net "M_L_DQ<40>")
		)
		(pad "EC36" smd circle
			(at -7.202932 25.417526)
			(size 0.4318 0.4318)
			(layers "F.Cu" "F.Mask" "F.Paste")
			(net "M_K_DQ<35>")
		)
		(pad "EC38" smd circle
			(at -5.485892 25.417526)
			(size 0.4318 0.4318)
			(layers "F.Cu" "F.Mask" "F.Paste")
			(net "M_K_DQS_DP<4>")
		)
		(pad "EC40" smd circle
			(at -3.769106 25.417526)
			(size 0.4318 0.4318)
			(layers "F.Cu" "F.Mask" "F.Paste")
			(net "M_K_DQ<32>")
		)
		(pad "EC42" smd custom
			(at -2.052066 25.417526 225)
			(size 0.10795 0.10795)
			(layers "F.Cu" "F.Mask" "F.Paste")
			(net "GND")
			(options
				(clearance outline)
				(anchor circle)
			)
			(primitives
				(gr_poly
					(pts
						(arc
							(start 0.2159 -0.0381)
							(mid 0 -0.254)
							(end -0.2159 -0.0381)
						)
						(arc
							(start -0.2159 0.0381)
							(mid 0 0.254)
							(end 0.2159 0.0381)
						)
					)
					(width 0)
					(fill yes)
				)
			)
		)
	)
)
